FILE_TYPE=LIBRARY_PARTS;
primitive '74LVC2G17GW';
  pin
    'VCC':
      PIN_NUMBER='(5)';
      PINUSE='POWER';
      NO_LOAD_CHECK='Both';
      NO_IO_CHECK='Both';
      NO_ASSERT_CHECK='TRUE';
      NO_DIR_CHECK='TRUE';
      ALLOW_CONNECT='TRUE';
    'B1':
      PIN_NUMBER='(4)';
      OUTPUT_LOAD='(1.0,-1.0)';
    'GND':
      PIN_NUMBER='(2)';
      PINUSE='POWER';
      NO_LOAD_CHECK='Both';
      NO_IO_CHECK='Both';
      NO_ASSERT_CHECK='TRUE';
      NO_DIR_CHECK='TRUE';
      ALLOW_CONNECT='TRUE';
    'A0':
      PIN_NUMBER='(1)';
      INPUT_LOAD='(-0.01,0.01)';
    'A1':
      PIN_NUMBER='(3)';
      INPUT_LOAD='(-0.01,0.01)';
    'B0':
      PIN_NUMBER='(6)';
      OUTPUT_LOAD='(1.0,-1.0)';
  end_pin;
  body
    PART_NAME='74LVC2G17GW';
    BODY_NAME='74LVC2G17GW';
    PHYS_DES_PREFIX='U';
    CLASS='IC';
  end_body;
end_primitive;

END.
